# S9S_MB_2U (Grand Teton) — schematic netlist excerpt (pin names and nets, part order shuffled) for the footprints in the layout excerpt that follows; sources: Cadence DE-HDL packaged netlist, KiCad conversion of 03242023_DA0F0TMBIJ0_F0T_Motherboard_J_brd_V01_OCP.brd

R3223  Q_RES  2K 1% CHIP  pkg 0402LF  page 236 : A = SMB_S3M_CPU0_PIROM_3V3AUX_SDA ; B = P3V3_AUX
R3461  Q_RES  54.9K 1% CHIP  pkg 0402LF  page 150 : A = P3V3_AUX ; B = GPU_NVS_PWR_BRAKE_N_R
PL101  Q_INDUCTOR  100NH/16A IND  pkg SMLF  page 272 : \1\ = P12V_AUX ; \2\ = SW_P12V_PVCCFA_EHV_FIVRA_CPU0_R

(kicad_pcb
	(version 20260206)
	(generator "pcbnew")
	(generator_version "10.0")
	(general
		(thickness 1.6)
		(legacy_teardrops no)
	)
	(paper "A4")
	(title_block
		(title "03242023_DA0F0TMBIJ0_F0T_Motherboard_J_brd_V01_OCP.brd")
		(comment 1 "Grand Teton / footprints 3564-3566 of 6105")
	)
	(layers
		(0 "F.Cu" signal "TOP")
		(4 "In1.Cu" signal "GND")
		(6 "In2.Cu" signal "IN1")
		(8 "In3.Cu" signal "GND1")
		(10 "In4.Cu" signal "IN2")
		(12 "In5.Cu" signal "GND2")
		(14 "In6.Cu" signal "IN3")
		(16 "In7.Cu" signal "GND3")
		(18 "In8.Cu" signal "VCC")
		(20 "In9.Cu" signal "VCC1")
		(22 "In10.Cu" signal "GND4")
		(24 "In11.Cu" signal "IN4")
		(26 "In12.Cu" signal "GND5")
		(28 "In13.Cu" signal "IN5")
		(30 "In14.Cu" signal "GND6")
		(32 "In15.Cu" signal "IN6")
		(34 "In16.Cu" signal "GND7")
		(2 "B.Cu" signal "BOTTOM")
		(9 "F.Adhes" user "F.Adhesive")
		(11 "B.Adhes" user "B.Adhesive")
		(13 "F.Paste" user "Package Geometry/Pastemask Top")
		(15 "B.Paste" user "Package Geometry/Pastemask Bottom")
		(5 "F.SilkS" user "Ref Des/Silkscreen Top")
		(7 "B.SilkS" user "Ref Des/Silkscreen Bottom")
		(1 "F.Mask" user "Board Geometry/Soldermask Top")
		(3 "B.Mask" user "Board Geometry/Soldermask Bottom")
		(17 "Dwgs.User" user "User.Drawings")
		(19 "Cmts.User" user "User.Comments")
		(21 "Eco1.User" user "User.Eco1")
		(23 "Eco2.User" user "User.Eco2")
		(25 "Edge.Cuts" user "Board Geometry/Outline")
		(27 "Margin" user)
		(31 "F.CrtYd" user "Package Geometry/Place Bound Top")
		(29 "B.CrtYd" user "Package Geometry/Place Bound Bottom")
		(35 "F.Fab" user "Ref Des/Assembly Top")
		(33 "B.Fab" user "Ref Des/Assembly Bottom")
	)
	(footprint ""
		(layer "F.Cu")
		(at 101.833934 -391.61974)
		(property "Reference" "R3461"
			(at 0 0 0)
			(layer "F.SilkS")
			(hide yes)
			(effects
				(font
					(size 1.27 1.27)
				)
			)
		)
		(property "Value" ""
			(at 0 0 0)
			(layer "F.Fab")
			(effects
				(font
					(size 1.27 1.27)
				)
			)
		)
		(duplicate_pad_numbers_are_jumpers no)
		(fp_line
			(start -0.7874 -0.4064)
			(end 0.7874 -0.4064)
			(stroke
				(width 0.1524)
				(type default)
			)
			(layer "F.SilkS")
		)
		(fp_line
			(start -0.7874 0.4064)
			(end -0.7874 -0.4064)
			(stroke
				(width 0.1524)
				(type default)
			)
			(layer "F.SilkS")
		)
		(fp_line
			(start 0.7874 -0.4064)
			(end 0.7874 0.4064)
			(stroke
				(width 0.1524)
				(type default)
			)
			(layer "F.SilkS")
		)
		(fp_line
			(start 0.7874 0.4064)
			(end -0.7874 0.4064)
			(stroke
				(width 0.1524)
				(type default)
			)
			(layer "F.SilkS")
		)
		(fp_line
			(start -0.67945 -0.305054)
			(end -0.12065 -0.305054)
			(stroke
				(width 0.1)
				(type default)
			)
			(layer "F.Fab")
		)
		(fp_line
			(start -0.67945 0.3048)
			(end -0.67945 -0.305054)
			(stroke
				(width 0.1)
				(type default)
			)
			(layer "F.Fab")
		)
		(fp_line
			(start -0.12065 -0.305054)
			(end -0.12065 -0.2794)
			(stroke
				(width 0.1)
				(type default)
			)
			(layer "F.Fab")
		)
		(fp_line
			(start -0.12065 -0.2794)
			(end 0.12065 -0.2794)
			(stroke
				(width 0.1)
				(type default)
			)
			(layer "F.Fab")
		)
		(fp_line
			(start -0.12065 0.2794)
			(end -0.12065 0.3048)
			(stroke
				(width 0.1)
				(type default)
			)
			(layer "F.Fab")
		)
		(fp_line
			(start -0.12065 0.3048)
			(end -0.67945 0.3048)
			(stroke
				(width 0.1)
				(type default)
			)
			(layer "F.Fab")
		)
		(fp_line
			(start 0.120396 0.2794)
			(end -0.12065 0.2794)
			(stroke
				(width 0.1)
				(type default)
			)
			(layer "F.Fab")
		)
		(fp_line
			(start 0.120396 0.3048)
			(end 0.120396 0.2794)
			(stroke
				(width 0.1)
				(type default)
			)
			(layer "F.Fab")
		)
		(fp_line
			(start 0.12065 -0.3048)
			(end 0.67945 -0.3048)
			(stroke
				(width 0.1)
				(type default)
			)
			(layer "F.Fab")
		)
		(fp_line
			(start 0.12065 -0.2794)
			(end 0.12065 -0.3048)
			(stroke
				(width 0.1)
				(type default)
			)
			(layer "F.Fab")
		)
		(fp_line
			(start 0.67945 -0.3048)
			(end 0.67945 0.3048)
			(stroke
				(width 0.1)
				(type default)
			)
			(layer "F.Fab")
		)
		(fp_line
			(start 0.67945 0.3048)
			(end 0.120396 0.3048)
			(stroke
				(width 0.1)
				(type default)
			)
			(layer "F.Fab")
		)
		(pad "1" smd circle
			(at -0.40005 0)
			(size 0 0)
			(layers "F.Cu" "F.Mask" "F.Paste")
			(net "P3V3_AUX")
		)
		(pad "2" smd circle
			(at 0.40005 0)
			(size 0 0)
			(layers "F.Cu" "F.Mask" "F.Paste")
			(net "GPU_NVS_PWR_BRAKE_N_R")
		)
	)
	(footprint ""
		(layer "F.Cu")
		(at 418.2491 -371.783356)
		(property "Reference" "PL101"
			(at -1.12014 -4.478528 0)
			(unlocked yes)
			(layer "F.SilkS")
			(effects
				(font
					(size 0.7874 0.5842)
					(thickness 0.1524)
				)
				(justify left)
			)
		)
		(property "Value" ""
			(at 0 0 0)
			(layer "F.Fab")
			(effects
				(font
					(size 1.27 1.27)
				)
			)
		)
		(duplicate_pad_numbers_are_jumpers no)
		(fp_line
			(start -2.249932 -2.249932)
			(end 2.249932 -2.249932)
			(stroke
				(width 0.1524)
				(type default)
			)
			(layer "F.SilkS")
		)
		(fp_line
			(start -2.249932 -1.3843)
			(end -2.249932 -2.249932)
			(stroke
				(width 0.1524)
				(type default)
			)
			(layer "F.SilkS")
		)
		(fp_line
			(start -2.249932 2.249932)
			(end -2.249932 1.3843)
			(stroke
				(width 0.1524)
				(type default)
			)
			(layer "F.SilkS")
		)
		(fp_line
			(start 2.249932 -2.249932)
			(end 2.249932 -1.3843)
			(stroke
				(width 0.1524)
				(type default)
			)
			(layer "F.SilkS")
		)
		(fp_line
			(start 2.249932 1.3843)
			(end 2.249932 2.249932)
			(stroke
				(width 0.1524)
				(type default)
			)
			(layer "F.SilkS")
		)
		(fp_line
			(start 2.249932 2.249932)
			(end -2.249932 2.249932)
			(stroke
				(width 0.1524)
				(type default)
			)
			(layer "F.SilkS")
		)
		(fp_line
			(start -2.249932 -2.249932)
			(end 2.249932 -2.249932)
			(stroke
				(width 0.1)
				(type default)
			)
			(layer "F.Fab")
		)
		(fp_line
			(start -2.249932 2.249932)
			(end -2.249932 -2.249932)
			(stroke
				(width 0.1)
				(type default)
			)
			(layer "F.Fab")
		)
		(fp_line
			(start 2.249932 -2.249932)
			(end 2.249932 2.249932)
			(stroke
				(width 0.1)
				(type default)
			)
			(layer "F.Fab")
		)
		(fp_line
			(start 2.249932 2.249932)
			(end -2.249932 2.249932)
			(stroke
				(width 0.1)
				(type default)
			)
			(layer "F.Fab")
		)
		(pad "1" smd rect
			(at -1.82499 0)
			(size 1.0668 2.5146)
			(layers "F.Cu" "F.Mask" "F.Paste")
			(net "P12V_AUX")
		)
		(pad "2" smd rect
			(at 1.82499 0)
			(size 1.0668 2.5146)
			(layers "F.Cu" "F.Mask" "F.Paste")
			(net "SW_P12V_PVCCFA_EHV_FIVRA_CPU0_R")
		)
	)
	(footprint ""
		(layer "F.Cu")
		(at 154.34945 -81.889346 -90)
		(property "Reference" "R3223"
			(at 0 0 270)
			(layer "F.SilkS")
			(hide yes)
			(effects
				(font
					(size 1.27 1.27)
				)
			)
		)
		(property "Value" ""
			(at 0 0 270)
			(layer "F.Fab")
			(effects
				(font
					(size 1.27 1.27)
				)
			)
		)
		(duplicate_pad_numbers_are_jumpers no)
		(fp_line
			(start -0.7874 0.4064)
			(end -0.7874 -0.4064)
			(stroke
				(width 0.1524)
				(type default)
			)
			(layer "F.SilkS")
		)
		(fp_line
			(start 0.7874 0.4064)
			(end -0.7874 0.4064)
			(stroke
				(width 0.1524)
				(type default)
			)
			(layer "F.SilkS")
		)
		(fp_line
			(start -0.7874 -0.4064)
			(end 0.7874 -0.4064)
			(stroke
				(width 0.1524)
				(type default)
			)
			(layer "F.SilkS")
		)
		(fp_line
			(start 0.7874 -0.4064)
			(end 0.7874 0.4064)
			(stroke
				(width 0.1524)
				(type default)
			)
			(layer "F.SilkS")
		)
		(fp_line
			(start -0.67945 0.3048)
			(end -0.67945 -0.305054)
			(stroke
				(width 0.1)
				(type default)
			)
			(layer "F.Fab")
		)
		(fp_line
			(start -0.12065 0.3048)
			(end -0.67945 0.3048)
			(stroke
				(width 0.1)
				(type default)
			)
			(layer "F.Fab")
		)
		(fp_line
			(start 0.120396 0.3048)
			(end 0.120396 0.2794)
			(stroke
				(width 0.1)
				(type default)
			)
			(layer "F.Fab")
		)
		(fp_line
			(start 0.67945 0.3048)
			(end 0.120396 0.3048)
			(stroke
				(width 0.1)
				(type default)
			)
			(layer "F.Fab")
		)
		(fp_line
			(start -0.12065 0.2794)
			(end -0.12065 0.3048)
			(stroke
				(width 0.1)
				(type default)
			)
			(layer "F.Fab")
		)
		(fp_line
			(start 0.120396 0.2794)
			(end -0.12065 0.2794)
			(stroke
				(width 0.1)
				(type default)
			)
			(layer "F.Fab")
		)
		(fp_line
			(start -0.12065 -0.2794)
			(end 0.12065 -0.2794)
			(stroke
				(width 0.1)
				(type default)
			)
			(layer "F.Fab")
		)
		(fp_line
			(start 0.12065 -0.2794)
			(end 0.12065 -0.3048)
			(stroke
				(width 0.1)
				(type default)
			)
			(layer "F.Fab")
		)
		(fp_line
			(start 0.12065 -0.3048)
			(end 0.67945 -0.3048)
			(stroke
				(width 0.1)
				(type default)
			)
			(layer "F.Fab")
		)
		(fp_line
			(start 0.67945 -0.3048)
			(end 0.67945 0.3048)
			(stroke
				(width 0.1)
				(type default)
			)
			(layer "F.Fab")
		)
		(fp_line
			(start -0.67945 -0.305054)
			(end -0.12065 -0.305054)
			(stroke
				(width 0.1)
				(type default)
			)
			(layer "F.Fab")
		)
		(fp_line
			(start -0.12065 -0.305054)
			(end -0.12065 -0.2794)
			(stroke
				(width 0.1)
				(type default)
			)
			(layer "F.Fab")
		)
		(pad "1" smd circle
			(at -0.40005 0 270)
			(size 0 0)
			(layers "F.Cu" "F.Mask" "F.Paste")
			(net "SMB_S3M_CPU0_PIROM_3V3AUX_SDA")
		)
		(pad "2" smd circle
			(at 0.40005 0 270)
			(size 0 0)
			(layers "F.Cu" "F.Mask" "F.Paste")
			(net "P3V3_AUX")
		)
	)
)
